(kicad_pcb
	(version 20260206)
	(generator "pcbnew")
	(generator_version "10.0")
	(general
		(thickness 1.6)
		(legacy_teardrops no)
	)
	(paper "A4")
	(title_block
		(title "12092022_DA0F0TFB6D0_F0T_FAN_BOARD_MP5048_D_brd_v02_OCP.brd")
		(comment 1 "Grand Teton / footprints 447-451 of 924")
	)
	(layers
		(0 "F.Cu" signal "TOP")
		(4 "In1.Cu" signal "GND")
		(6 "In2.Cu" signal "IN1")
		(8 "In3.Cu" signal "IN2")
		(10 "In4.Cu" signal "GND1")
		(2 "B.Cu" signal "BOTTOM")
		(9 "F.Adhes" user "F.Adhesive")
		(11 "B.Adhes" user "B.Adhesive")
		(13 "F.Paste" user "Package Geometry/Pastemask Top")
		(15 "B.Paste" user "Package Geometry/Pastemask Bottom")
		(5 "F.SilkS" user "Ref Des/Silkscreen Top")
		(7 "B.SilkS" user "Ref Des/Silkscreen Bottom")
		(1 "F.Mask" user "Board Geometry/Soldermask Top")
		(3 "B.Mask" user "Board Geometry/Soldermask Bottom")
		(17 "Dwgs.User" user "User.Drawings")
		(19 "Cmts.User" user "User.Comments")
		(21 "Eco1.User" user "User.Eco1")
		(23 "Eco2.User" user "User.Eco2")
		(25 "Edge.Cuts" user "Board Geometry/Outline")
		(27 "Margin" user)
		(31 "F.CrtYd" user "Package Geometry/Place Bound Top")
		(29 "B.CrtYd" user "Package Geometry/Place Bound Bottom")
		(35 "F.Fab" user "Ref Des/Assembly Top")
		(33 "B.Fab" user "Ref Des/Assembly Bottom")
	)
	(footprint ""
		(layer "F.Cu")
		(at 4.445 -249.555 -90)
		(property "Reference" "PR64"
			(at 0 0 270)
			(layer "F.SilkS")
			(hide yes)
			(effects
				(font
					(size 1.27 1.27)
				)
			)
		)
		(property "Value" ""
			(at 0 0 270)
			(layer "F.Fab")
			(effects
				(font
					(size 1.27 1.27)
				)
			)
		)
		(duplicate_pad_numbers_are_jumpers no)
		(fp_line
			(start -0.7874 0.4064)
			(end -0.7874 -0.4064)
			(stroke
				(width 0.1524)
				(type default)
			)
			(layer "F.SilkS")
		)
		(fp_line
			(start 0.7874 0.4064)
			(end -0.7874 0.4064)
			(stroke
				(width 0.1524)
				(type default)
			)
			(layer "F.SilkS")
		)
		(fp_line
			(start -0.7874 -0.4064)
			(end 0.7874 -0.4064)
			(stroke
				(width 0.1524)
				(type default)
			)
			(layer "F.SilkS")
		)
		(fp_line
			(start 0.7874 -0.4064)
			(end 0.7874 0.4064)
			(stroke
				(width 0.1524)
				(type default)
			)
			(layer "F.SilkS")
		)
		(fp_line
			(start -0.67945 0.3048)
			(end -0.67945 -0.305054)
			(stroke
				(width 0.1)
				(type default)
			)
			(layer "F.Fab")
		)
		(fp_line
			(start -0.12065 0.3048)
			(end -0.67945 0.3048)
			(stroke
				(width 0.1)
				(type default)
			)
			(layer "F.Fab")
		)
		(fp_line
			(start 0.120396 0.3048)
			(end 0.120396 0.2794)
			(stroke
				(width 0.1)
				(type default)
			)
			(layer "F.Fab")
		)
		(fp_line
			(start 0.67945 0.3048)
			(end 0.120396 0.3048)
			(stroke
				(width 0.1)
				(type default)
			)
			(layer "F.Fab")
		)
		(fp_line
			(start -0.12065 0.2794)
			(end -0.12065 0.3048)
			(stroke
				(width 0.1)
				(type default)
			)
			(layer "F.Fab")
		)
		(fp_line
			(start 0.120396 0.2794)
			(end -0.12065 0.2794)
			(stroke
				(width 0.1)
				(type default)
			)
			(layer "F.Fab")
		)
		(fp_line
			(start -0.12065 -0.2794)
			(end 0.12065 -0.2794)
			(stroke
				(width 0.1)
				(type default)
			)
			(layer "F.Fab")
		)
		(fp_line
			(start 0.12065 -0.2794)
			(end 0.12065 -0.3048)
			(stroke
				(width 0.1)
				(type default)
			)
			(layer "F.Fab")
		)
		(fp_line
			(start 0.12065 -0.3048)
			(end 0.67945 -0.3048)
			(stroke
				(width 0.1)
				(type default)
			)
			(layer "F.Fab")
		)
		(fp_line
			(start 0.67945 -0.3048)
			(end 0.67945 0.3048)
			(stroke
				(width 0.1)
				(type default)
			)
			(layer "F.Fab")
		)
		(fp_line
			(start -0.67945 -0.305054)
			(end -0.12065 -0.305054)
			(stroke
				(width 0.1)
				(type default)
			)
			(layer "F.Fab")
		)
		(fp_line
			(start -0.12065 -0.305054)
			(end -0.12065 -0.2794)
			(stroke
				(width 0.1)
				(type default)
			)
			(layer "F.Fab")
		)
		(pad "1" smd rect
			(at -0.40005 0 90)
			(size 0.4572 0.508)
			(layers "F.Cu" "F.Mask" "F.Paste")
			(net "FAN_6_FAULT_R")
		)
		(pad "2" smd rect
			(at 0.40005 0 90)
			(size 0.4572 0.508)
			(layers "F.Cu" "F.Mask" "F.Paste")
			(net "FAN_6_FAULT")
		)
	)
	(footprint ""
		(layer "F.Cu")
		(at 36.322 -209.959956)
		(property "Reference" "D133"
			(at 2.667 -0.960374 0)
			(unlocked yes)
			(layer "F.SilkS")
			(effects
				(font
					(size 0.7874 0.5842)
					(thickness 0.1524)
				)
				(justify left)
			)
		)
		(property "Value" ""
			(at 0 0 0)
			(layer "F.Fab")
			(effects
				(font
					(size 1.27 1.27)
				)
			)
		)
		(duplicate_pad_numbers_are_jumpers no)
		(fp_line
			(start -1.651 -0.7112)
			(end 2.032 -0.7112)
			(stroke
				(width 0.1524)
				(type default)
			)
			(layer "F.SilkS")
		)
		(fp_line
			(start -1.651 0.7112)
			(end -1.651 -0.7112)
			(stroke
				(width 0.1524)
				(type default)
			)
			(layer "F.SilkS")
		)
		(fp_line
			(start -0.299974 -0.500126)
			(end -0.299974 0.500126)
			(stroke
				(width 0.1524)
				(type default)
			)
			(layer "F.SilkS")
		)
		(fp_line
			(start -0.299974 0.500126)
			(end 0.199898 0)
			(stroke
				(width 0.1524)
				(type default)
			)
			(layer "F.SilkS")
		)
		(fp_line
			(start 0.199898 0)
			(end -0.299974 -0.500126)
			(stroke
				(width 0.1524)
				(type default)
			)
			(layer "F.SilkS")
		)
		(fp_line
			(start 0.299974 -0.500126)
			(end 0.299974 0.500126)
			(stroke
				(width 0.1524)
				(type default)
			)
			(layer "F.SilkS")
		)
		(fp_line
			(start 1.651 -0.6858)
			(end 1.651 0.6858)
			(stroke
				(width 0.1524)
				(type default)
			)
			(layer "F.SilkS")
		)
		(fp_line
			(start 1.778 0.6858)
			(end 1.778 -0.6858)
			(stroke
				(width 0.1524)
				(type default)
			)
			(layer "F.SilkS")
		)
		(fp_line
			(start 1.905 -0.6858)
			(end 1.905 0.6858)
			(stroke
				(width 0.1524)
				(type default)
			)
			(layer "F.SilkS")
		)
		(fp_line
			(start 2.032 -0.7112)
			(end 2.032 0.7112)
			(stroke
				(width 0.1524)
				(type default)
			)
			(layer "F.SilkS")
		)
		(fp_line
			(start 2.032 0.7112)
			(end -1.651 0.7112)
			(stroke
				(width 0.1524)
				(type default)
			)
			(layer "F.SilkS")
		)
		(fp_line
			(start -1.35001 -0.225044)
			(end -0.899922 -0.225044)
			(stroke
				(width 0.1)
				(type default)
			)
			(layer "F.Fab")
		)
		(fp_line
			(start -1.35001 0.175006)
			(end -1.35001 -0.225044)
			(stroke
				(width 0.1)
				(type default)
			)
			(layer "F.Fab")
		)
		(fp_line
			(start -0.899922 -0.700024)
			(end 0.899922 -0.700024)
			(stroke
				(width 0.1)
				(type default)
			)
			(layer "F.Fab")
		)
		(fp_line
			(start -0.899922 -0.225044)
			(end -0.899922 -0.700024)
			(stroke
				(width 0.1)
				(type default)
			)
			(layer "F.Fab")
		)
		(fp_line
			(start -0.899922 0.175006)
			(end -1.35001 0.175006)
			(stroke
				(width 0.1)
				(type default)
			)
			(layer "F.Fab")
		)
		(fp_line
			(start -0.899922 0.700024)
			(end -0.899922 0.175006)
			(stroke
				(width 0.1)
				(type default)
			)
			(layer "F.Fab")
		)
		(fp_line
			(start -0.299974 -0.500126)
			(end -0.299974 0.500126)
			(stroke
				(width 0.1)
				(type default)
			)
			(layer "F.Fab")
		)
		(fp_line
			(start -0.299974 0.500126)
			(end 0.199898 0)
			(stroke
				(width 0.1)
				(type default)
			)
			(layer "F.Fab")
		)
		(fp_line
			(start 0.199898 0)
			(end -0.299974 -0.500126)
			(stroke
				(width 0.1)
				(type default)
			)
			(layer "F.Fab")
		)
		(fp_line
			(start 0.299974 -0.500126)
			(end 0.299974 0.500126)
			(stroke
				(width 0.1)
				(type default)
			)
			(layer "F.Fab")
		)
		(fp_line
			(start 0.899922 -0.700024)
			(end 0.899922 -0.225044)
			(stroke
				(width 0.1)
				(type default)
			)
			(layer "F.Fab")
		)
		(fp_line
			(start 0.899922 -0.225044)
			(end 1.35001 -0.225044)
			(stroke
				(width 0.1)
				(type default)
			)
			(layer "F.Fab")
		)
		(fp_line
			(start 0.899922 0.175006)
			(end 0.899922 0.700024)
			(stroke
				(width 0.1)
				(type default)
			)
			(layer "F.Fab")
		)
		(fp_line
			(start 0.899922 0.700024)
			(end -0.899922 0.700024)
			(stroke
				(width 0.1)
				(type default)
			)
			(layer "F.Fab")
		)
		(fp_line
			(start 1.35001 -0.225044)
			(end 1.35001 0.175006)
			(stroke
				(width 0.1)
				(type default)
			)
			(layer "F.Fab")
		)
		(fp_line
			(start 1.35001 0.175006)
			(end 0.899922 0.175006)
			(stroke
				(width 0.1)
				(type default)
			)
			(layer "F.Fab")
		)
		(fp_text user "+"
			(at -2.667 0.822706 0)
			(unlocked yes)
			(layer "F.SilkS")
			(effects
				(font
					(size 1.905 1.4224)
					(thickness 0.1524)
				)
				(justify left)
			)
		)
		(fp_text user "-"
			(at 0.508 -1.209294 0)
			(unlocked yes)
			(layer "F.SilkS")
			(effects
				(font
					(size 1.905 1.4224)
					(thickness 0.1524)
				)
				(justify left)
			)
		)
		(fp_text user "+"
			(at -2.794 -0.19685 0)
			(unlocked yes)
			(layer "F.Fab")
			(effects
				(font
					(size 1.905 1.4224)
					(thickness 0.1524)
				)
				(justify left)
			)
		)
		(fp_text user "-"
			(at 1.8288 -0.24765 0)
			(unlocked yes)
			(layer "F.Fab")
			(effects
				(font
					(size 1.905 1.4224)
					(thickness 0.1524)
				)
				(justify left)
			)
		)
		(pad "1" smd rect
			(at -1.0922 0 180)
			(size 0.8128 0.8636)
			(layers "F.Cu" "F.Mask" "F.Paste")
			(net "FAN_1_TACH_IL_R")
		)
		(pad "2" smd rect
			(at 1.0922 0)
			(size 0.8128 0.8636)
			(layers "F.Cu" "F.Mask" "F.Paste")
			(net "FAN_1_TACH_IL_D")
		)
	)
	(footprint ""
		(layer "F.Cu")
		(at 37.82695 -123.698 180)
		(property "Reference" "R5608"
			(at 0 0 180)
			(layer "F.SilkS")
			(hide yes)
			(effects
				(font
					(size 1.27 1.27)
				)
			)
		)
		(property "Value" ""
			(at 0 0 180)
			(layer "F.Fab")
			(effects
				(font
					(size 1.27 1.27)
				)
			)
		)
		(duplicate_pad_numbers_are_jumpers no)
		(fp_line
			(start 0.7874 0.4064)
			(end -0.7874 0.4064)
			(stroke
				(width 0.1524)
				(type default)
			)
			(layer "F.SilkS")
		)
		(fp_line
			(start 0.7874 -0.4064)
			(end 0.7874 0.4064)
			(stroke
				(width 0.1524)
				(type default)
			)
			(layer "F.SilkS")
		)
		(fp_line
			(start -0.7874 0.4064)
			(end -0.7874 -0.4064)
			(stroke
				(width 0.1524)
				(type default)
			)
			(layer "F.SilkS")
		)
		(fp_line
			(start -0.7874 -0.4064)
			(end 0.7874 -0.4064)
			(stroke
				(width 0.1524)
				(type default)
			)
			(layer "F.SilkS")
		)
		(fp_line
			(start 0.67945 0.3048)
			(end 0.120396 0.3048)
			(stroke
				(width 0.1)
				(type default)
			)
			(layer "F.Fab")
		)
		(fp_line
			(start 0.67945 -0.3048)
			(end 0.67945 0.3048)
			(stroke
				(width 0.1)
				(type default)
			)
			(layer "F.Fab")
		)
		(fp_line
			(start 0.12065 -0.2794)
			(end 0.12065 -0.3048)
			(stroke
				(width 0.1)
				(type default)
			)
			(layer "F.Fab")
		)
		(fp_line
			(start 0.12065 -0.3048)
			(end 0.67945 -0.3048)
			(stroke
				(width 0.1)
				(type default)
			)
			(layer "F.Fab")
		)
		(fp_line
			(start 0.120396 0.3048)
			(end 0.120396 0.2794)
			(stroke
				(width 0.1)
				(type default)
			)
			(layer "F.Fab")
		)
		(fp_line
			(start 0.120396 0.2794)
			(end -0.12065 0.2794)
			(stroke
				(width 0.1)
				(type default)
			)
			(layer "F.Fab")
		)
		(fp_line
			(start -0.12065 0.3048)
			(end -0.67945 0.3048)
			(stroke
				(width 0.1)
				(type default)
			)
			(layer "F.Fab")
		)
		(fp_line
			(start -0.12065 0.2794)
			(end -0.12065 0.3048)
			(stroke
				(width 0.1)
				(type default)
			)
			(layer "F.Fab")
		)
		(fp_line
			(start -0.12065 -0.2794)
			(end 0.12065 -0.2794)
			(stroke
				(width 0.1)
				(type default)
			)
			(layer "F.Fab")
		)
		(fp_line
			(start -0.12065 -0.305054)
			(end -0.12065 -0.2794)
			(stroke
				(width 0.1)
				(type default)
			)
			(layer "F.Fab")
		)
		(fp_line
			(start -0.67945 0.3048)
			(end -0.67945 -0.305054)
			(stroke
				(width 0.1)
				(type default)
			)
			(layer "F.Fab")
		)
		(fp_line
			(start -0.67945 -0.305054)
			(end -0.12065 -0.305054)
			(stroke
				(width 0.1)
				(type default)
			)
			(layer "F.Fab")
		)
		(pad "1" smd rect
			(at -0.40005 0)
			(size 0.4572 0.508)
			(layers "F.Cu" "F.Mask" "F.Paste")
			(net "FAN_3_TACH_OL")
		)
		(pad "2" smd rect
			(at 0.40005 0)
			(size 0.4572 0.508)
			(layers "F.Cu" "F.Mask" "F.Paste")
			(net "FAN_3_TACH_OL_R1")
		)
	)
	(footprint ""
		(layer "F.Cu")
		(at 19.05 -143.891 -90)
		(property "Reference" "R5471"
			(at 0 0 270)
			(layer "F.SilkS")
			(hide yes)
			(effects
				(font
					(size 1.27 1.27)
				)
			)
		)
		(property "Value" ""
			(at 0 0 270)
			(layer "F.Fab")
			(effects
				(font
					(size 1.27 1.27)
				)
			)
		)
		(duplicate_pad_numbers_are_jumpers no)
		(fp_line
			(start -0.7874 0.4064)
			(end -0.7874 -0.4064)
			(stroke
				(width 0.1524)
				(type default)
			)
			(layer "F.SilkS")
		)
		(fp_line
			(start 0.7874 0.4064)
			(end -0.7874 0.4064)
			(stroke
				(width 0.1524)
				(type default)
			)
			(layer "F.SilkS")
		)
		(fp_line
			(start -0.7874 -0.4064)
			(end 0.7874 -0.4064)
			(stroke
				(width 0.1524)
				(type default)
			)
			(layer "F.SilkS")
		)
		(fp_line
			(start 0.7874 -0.4064)
			(end 0.7874 0.4064)
			(stroke
				(width 0.1524)
				(type default)
			)
			(layer "F.SilkS")
		)
		(fp_line
			(start -0.67945 0.3048)
			(end -0.67945 -0.305054)
			(stroke
				(width 0.1)
				(type default)
			)
			(layer "F.Fab")
		)
		(fp_line
			(start -0.12065 0.3048)
			(end -0.67945 0.3048)
			(stroke
				(width 0.1)
				(type default)
			)
			(layer "F.Fab")
		)
		(fp_line
			(start 0.120396 0.3048)
			(end 0.120396 0.2794)
			(stroke
				(width 0.1)
				(type default)
			)
			(layer "F.Fab")
		)
		(fp_line
			(start 0.67945 0.3048)
			(end 0.120396 0.3048)
			(stroke
				(width 0.1)
				(type default)
			)
			(layer "F.Fab")
		)
		(fp_line
			(start -0.12065 0.2794)
			(end -0.12065 0.3048)
			(stroke
				(width 0.1)
				(type default)
			)
			(layer "F.Fab")
		)
		(fp_line
			(start 0.120396 0.2794)
			(end -0.12065 0.2794)
			(stroke
				(width 0.1)
				(type default)
			)
			(layer "F.Fab")
		)
		(fp_line
			(start -0.12065 -0.2794)
			(end 0.12065 -0.2794)
			(stroke
				(width 0.1)
				(type default)
			)
			(layer "F.Fab")
		)
		(fp_line
			(start 0.12065 -0.2794)
			(end 0.12065 -0.3048)
			(stroke
				(width 0.1)
				(type default)
			)
			(layer "F.Fab")
		)
		(fp_line
			(start 0.12065 -0.3048)
			(end 0.67945 -0.3048)
			(stroke
				(width 0.1)
				(type default)
			)
			(layer "F.Fab")
		)
		(fp_line
			(start 0.67945 -0.3048)
			(end 0.67945 0.3048)
			(stroke
				(width 0.1)
				(type default)
			)
			(layer "F.Fab")
		)
		(fp_line
			(start -0.67945 -0.305054)
			(end -0.12065 -0.305054)
			(stroke
				(width 0.1)
				(type default)
			)
			(layer "F.Fab")
		)
		(fp_line
			(start -0.12065 -0.305054)
			(end -0.12065 -0.2794)
			(stroke
				(width 0.1)
				(type default)
			)
			(layer "F.Fab")
		)
		(pad "1" smd circle
			(at -0.40005 0 270)
			(size 0 0)
			(layers "F.Cu" "F.Mask" "F.Paste")
			(net "PD_TCA9548_SML1_U321_A1")
		)
		(pad "2" smd circle
			(at 0.40005 0 270)
			(size 0 0)
			(layers "F.Cu" "F.Mask" "F.Paste")
			(net "GND")
		)
	)
	(footprint ""
		(layer "F.Cu")
		(at 3.248914 -252.095 90)
		(property "Reference" "C2071"
			(at 0 0 90)
			(layer "F.SilkS")
			(hide yes)
			(effects
				(font
					(size 1.27 1.27)
				)
			)
		)
		(property "Value" ""
			(at 0 0 90)
			(layer "F.Fab")
			(effects
				(font
					(size 1.27 1.27)
				)
			)
		)
		(duplicate_pad_numbers_are_jumpers no)
		(fp_line
			(start 0.7874 -0.4064)
			(end 0.7874 0.4064)
			(stroke
				(width 0.1524)
				(type default)
			)
			(layer "F.SilkS")
		)
		(fp_line
			(start -0.7874 -0.4064)
			(end 0.7874 -0.4064)
			(stroke
				(width 0.1524)
				(type default)
			)
			(layer "F.SilkS")
		)
		(fp_line
			(start 0.7874 0.4064)
			(end -0.7874 0.4064)
			(stroke
				(width 0.1524)
				(type default)
			)
			(layer "F.SilkS")
		)
		(fp_line
			(start -0.7874 0.4064)
			(end -0.7874 -0.4064)
			(stroke
				(width 0.1524)
				(type default)
			)
			(layer "F.SilkS")
		)
		(fp_line
			(start -0.12065 -0.305054)
			(end -0.12065 -0.2794)
			(stroke
				(width 0.1)
				(type default)
			)
			(layer "F.Fab")
		)
		(fp_line
			(start -0.67945 -0.305054)
			(end -0.12065 -0.305054)
			(stroke
				(width 0.1)
				(type default)
			)
			(layer "F.Fab")
		)
		(fp_line
			(start 0.67945 -0.3048)
			(end 0.67945 0.3048)
			(stroke
				(width 0.1)
				(type default)
			)
			(layer "F.Fab")
		)
		(fp_line
			(start 0.12065 -0.3048)
			(end 0.67945 -0.3048)
			(stroke
				(width 0.1)
				(type default)
			)
			(layer "F.Fab")
		)
		(fp_line
			(start 0.12065 -0.2794)
			(end 0.12065 -0.3048)
			(stroke
				(width 0.1)
				(type default)
			)
			(layer "F.Fab")
		)
		(fp_line
			(start -0.12065 -0.2794)
			(end 0.12065 -0.2794)
			(stroke
				(width 0.1)
				(type default)
			)
			(layer "F.Fab")
		)
		(fp_line
			(start 0.120396 0.2794)
			(end -0.12065 0.2794)
			(stroke
				(width 0.1)
				(type default)
			)
			(layer "F.Fab")
		)
		(fp_line
			(start -0.12065 0.2794)
			(end -0.12065 0.3048)
			(stroke
				(width 0.1)
				(type default)
			)
			(layer "F.Fab")
		)
		(fp_line
			(start 0.67945 0.3048)
			(end 0.120396 0.3048)
			(stroke
				(width 0.1)
				(type default)
			)
			(layer "F.Fab")
		)
		(fp_line
			(start 0.120396 0.3048)
			(end 0.120396 0.2794)
			(stroke
				(width 0.1)
				(type default)
			)
			(layer "F.Fab")
		)
		(fp_line
			(start -0.12065 0.3048)
			(end -0.67945 0.3048)
			(stroke
				(width 0.1)
				(type default)
			)
			(layer "F.Fab")
		)
		(fp_line
			(start -0.67945 0.3048)
			(end -0.67945 -0.305054)
			(stroke
				(width 0.1)
				(type default)
			)
			(layer "F.Fab")
		)
		(pad "1" smd circle
			(at -0.40005 0 90)
			(size 0 0)
			(layers "F.Cu" "F.Mask" "F.Paste")
			(net "P3V3_AUX")
		)
		(pad "2" smd circle
			(at 0.40005 0 90)
			(size 0 0)
			(layers "F.Cu" "F.Mask" "F.Paste")
			(net "GND")
		)
	)
)
